# S9S_MB_2U (Grand Teton) — schematic netlist excerpt (pin names and nets, part order shuffled) for the footprints in the layout excerpt that follows; sources: Cadence DE-HDL packaged netlist, KiCad conversion of 03242023_DA0F0TMBIJ0_F0T_Motherboard_J_brd_V01_OCP.brd

PC391  Q_CAP  100NF 50V 10% EMPTY  pkg C0402  page 296 : A = PVCCD_HV_CPU1_VCC ; B = GND
R1520  Q_RES  33.2 1% CHIP  pkg 0402LF  page 223 : A = RST_PCIE_CPU1_DEV_PERST_N ; B = RST_OCP_V3_2_N

(kicad_pcb
	(version 20260206)
	(generator "pcbnew")
	(generator_version "10.0")
	(general
		(thickness 1.6)
		(legacy_teardrops no)
	)
	(paper "A4")
	(title_block
		(title "03242023_DA0F0TMBIJ0_F0T_Motherboard_J_brd_V01_OCP.brd")
		(comment 1 "Grand Teton / footprints 2258-2259 of 6105")
	)
	(layers
		(0 "F.Cu" signal "TOP")
		(4 "In1.Cu" signal "GND")
		(6 "In2.Cu" signal "IN1")
		(8 "In3.Cu" signal "GND1")
		(10 "In4.Cu" signal "IN2")
		(12 "In5.Cu" signal "GND2")
		(14 "In6.Cu" signal "IN3")
		(16 "In7.Cu" signal "GND3")
		(18 "In8.Cu" signal "VCC")
		(20 "In9.Cu" signal "VCC1")
		(22 "In10.Cu" signal "GND4")
		(24 "In11.Cu" signal "IN4")
		(26 "In12.Cu" signal "GND5")
		(28 "In13.Cu" signal "IN5")
		(30 "In14.Cu" signal "GND6")
		(32 "In15.Cu" signal "IN6")
		(34 "In16.Cu" signal "GND7")
		(2 "B.Cu" signal "BOTTOM")
		(9 "F.Adhes" user "F.Adhesive")
		(11 "B.Adhes" user "B.Adhesive")
		(13 "F.Paste" user "Package Geometry/Pastemask Top")
		(15 "B.Paste" user "Package Geometry/Pastemask Bottom")
		(5 "F.SilkS" user "Ref Des/Silkscreen Top")
		(7 "B.SilkS" user "Ref Des/Silkscreen Bottom")
		(1 "F.Mask" user "Board Geometry/Soldermask Top")
		(3 "B.Mask" user "Board Geometry/Soldermask Bottom")
		(17 "Dwgs.User" user "User.Drawings")
		(19 "Cmts.User" user "User.Comments")
		(21 "Eco1.User" user "User.Eco1")
		(23 "Eco2.User" user "User.Eco2")
		(25 "Edge.Cuts" user "Board Geometry/Outline")
		(27 "Margin" user)
		(31 "F.CrtYd" user "Package Geometry/Place Bound Top")
		(29 "B.CrtYd" user "Package Geometry/Place Bound Bottom")
		(35 "F.Fab" user "Ref Des/Assembly Top")
		(33 "B.Fab" user "Ref Des/Assembly Bottom")
	)
	(footprint ""
		(layer "F.Cu")
		(at 31.540196 -168.02481)
		(property "Reference" "PC391"
			(at 0 0 0)
			(layer "F.SilkS")
			(hide yes)
			(effects
				(font
					(size 1.27 1.27)
				)
			)
		)
		(property "Value" ""
			(at 0 0 0)
			(layer "F.Fab")
			(effects
				(font
					(size 1.27 1.27)
				)
			)
		)
		(duplicate_pad_numbers_are_jumpers no)
		(fp_line
			(start -0.7874 -0.4064)
			(end 0.7874 -0.4064)
			(stroke
				(width 0.1524)
				(type default)
			)
			(layer "F.SilkS")
		)
		(fp_line
			(start -0.7874 0.4064)
			(end -0.7874 -0.4064)
			(stroke
				(width 0.1524)
				(type default)
			)
			(layer "F.SilkS")
		)
		(fp_line
			(start 0.7874 -0.4064)
			(end 0.7874 0.4064)
			(stroke
				(width 0.1524)
				(type default)
			)
			(layer "F.SilkS")
		)
		(fp_line
			(start 0.7874 0.4064)
			(end -0.7874 0.4064)
			(stroke
				(width 0.1524)
				(type default)
			)
			(layer "F.SilkS")
		)
		(fp_line
			(start -0.67945 -0.305054)
			(end -0.12065 -0.305054)
			(stroke
				(width 0.1)
				(type default)
			)
			(layer "F.Fab")
		)
		(fp_line
			(start -0.67945 0.3048)
			(end -0.67945 -0.305054)
			(stroke
				(width 0.1)
				(type default)
			)
			(layer "F.Fab")
		)
		(fp_line
			(start -0.12065 -0.305054)
			(end -0.12065 -0.2794)
			(stroke
				(width 0.1)
				(type default)
			)
			(layer "F.Fab")
		)
		(fp_line
			(start -0.12065 -0.2794)
			(end 0.12065 -0.2794)
			(stroke
				(width 0.1)
				(type default)
			)
			(layer "F.Fab")
		)
		(fp_line
			(start -0.12065 0.2794)
			(end -0.12065 0.3048)
			(stroke
				(width 0.1)
				(type default)
			)
			(layer "F.Fab")
		)
		(fp_line
			(start -0.12065 0.3048)
			(end -0.67945 0.3048)
			(stroke
				(width 0.1)
				(type default)
			)
			(layer "F.Fab")
		)
		(fp_line
			(start 0.120396 0.2794)
			(end -0.12065 0.2794)
			(stroke
				(width 0.1)
				(type default)
			)
			(layer "F.Fab")
		)
		(fp_line
			(start 0.120396 0.3048)
			(end 0.120396 0.2794)
			(stroke
				(width 0.1)
				(type default)
			)
			(layer "F.Fab")
		)
		(fp_line
			(start 0.12065 -0.3048)
			(end 0.67945 -0.3048)
			(stroke
				(width 0.1)
				(type default)
			)
			(layer "F.Fab")
		)
		(fp_line
			(start 0.12065 -0.2794)
			(end 0.12065 -0.3048)
			(stroke
				(width 0.1)
				(type default)
			)
			(layer "F.Fab")
		)
		(fp_line
			(start 0.67945 -0.3048)
			(end 0.67945 0.3048)
			(stroke
				(width 0.1)
				(type default)
			)
			(layer "F.Fab")
		)
		(fp_line
			(start 0.67945 0.3048)
			(end 0.120396 0.3048)
			(stroke
				(width 0.1)
				(type default)
			)
			(layer "F.Fab")
		)
		(pad "1" smd circle
			(at -0.40005 0)
			(size 0 0)
			(layers "F.Cu" "F.Mask" "F.Paste")
			(net "PVCCD_HV_CPU1_VCC")
		)
		(pad "2" smd circle
			(at 0.40005 0)
			(size 0 0)
			(layers "F.Cu" "F.Mask" "F.Paste")
			(net "GND")
		)
	)
	(footprint ""
		(layer "F.Cu")
		(at 88.655652 -36.288726 180)
		(property "Reference" "R1520"
			(at 0 0 180)
			(layer "F.SilkS")
			(hide yes)
			(effects
				(font
					(size 1.27 1.27)
				)
			)
		)
		(property "Value" ""
			(at 0 0 180)
			(layer "F.Fab")
			(effects
				(font
					(size 1.27 1.27)
				)
			)
		)
		(duplicate_pad_numbers_are_jumpers no)
		(fp_line
			(start 0.7874 0.4064)
			(end -0.7874 0.4064)
			(stroke
				(width 0.1524)
				(type default)
			)
			(layer "F.SilkS")
		)
		(fp_line
			(start 0.7874 -0.4064)
			(end 0.7874 0.4064)
			(stroke
				(width 0.1524)
				(type default)
			)
			(layer "F.SilkS")
		)
		(fp_line
			(start -0.7874 0.4064)
			(end -0.7874 -0.4064)
			(stroke
				(width 0.1524)
				(type default)
			)
			(layer "F.SilkS")
		)
		(fp_line
			(start -0.7874 -0.4064)
			(end 0.7874 -0.4064)
			(stroke
				(width 0.1524)
				(type default)
			)
			(layer "F.SilkS")
		)
		(fp_line
			(start 0.67945 0.3048)
			(end 0.120396 0.3048)
			(stroke
				(width 0.1)
				(type default)
			)
			(layer "F.Fab")
		)
		(fp_line
			(start 0.67945 -0.3048)
			(end 0.67945 0.3048)
			(stroke
				(width 0.1)
				(type default)
			)
			(layer "F.Fab")
		)
		(fp_line
			(start 0.12065 -0.2794)
			(end 0.12065 -0.3048)
			(stroke
				(width 0.1)
				(type default)
			)
			(layer "F.Fab")
		)
		(fp_line
			(start 0.12065 -0.3048)
			(end 0.67945 -0.3048)
			(stroke
				(width 0.1)
				(type default)
			)
			(layer "F.Fab")
		)
		(fp_line
			(start 0.120396 0.3048)
			(end 0.120396 0.2794)
			(stroke
				(width 0.1)
				(type default)
			)
			(layer "F.Fab")
		)
		(fp_line
			(start 0.120396 0.2794)
			(end -0.12065 0.2794)
			(stroke
				(width 0.1)
				(type default)
			)
			(layer "F.Fab")
		)
		(fp_line
			(start -0.12065 0.3048)
			(end -0.67945 0.3048)
			(stroke
				(width 0.1)
				(type default)
			)
			(layer "F.Fab")
		)
		(fp_line
			(start -0.12065 0.2794)
			(end -0.12065 0.3048)
			(stroke
				(width 0.1)
				(type default)
			)
			(layer "F.Fab")
		)
		(fp_line
			(start -0.12065 -0.2794)
			(end 0.12065 -0.2794)
			(stroke
				(width 0.1)
				(type default)
			)
			(layer "F.Fab")
		)
		(fp_line
			(start -0.12065 -0.305054)
			(end -0.12065 -0.2794)
			(stroke
				(width 0.1)
				(type default)
			)
			(layer "F.Fab")
		)
		(fp_line
			(start -0.67945 0.3048)
			(end -0.67945 -0.305054)
			(stroke
				(width 0.1)
				(type default)
			)
			(layer "F.Fab")
		)
		(fp_line
			(start -0.67945 -0.305054)
			(end -0.12065 -0.305054)
			(stroke
				(width 0.1)
				(type default)
			)
			(layer "F.Fab")
		)
		(pad "1" smd circle
			(at -0.40005 0 180)
			(size 0 0)
			(layers "F.Cu" "F.Mask" "F.Paste")
			(net "RST_PCIE_CPU1_DEV_PERST_N")
		)
		(pad "2" smd circle
			(at 0.40005 0 180)
			(size 0 0)
			(layers "F.Cu" "F.Mask" "F.Paste")
			(net "RST_OCP_V3_2_N")
		)
	)
)
